(kicad_pcb
	(version 20260206)
	(generator "pcbnew")
	(generator_version "10.0")
	(general
		(thickness 1.6)
		(legacy_teardrops no)
	)
	(paper "A4")
	(title_block
		(title "01162023_DA0F0TEBIF0_F0T_Expander_BD_F_brd_V02_OCP.brd")
		(comment 1 "Grand Teton / footprints 4229-4234 of 9728")
	)
	(layers
		(0 "F.Cu" signal "TOP")
		(4 "In1.Cu" signal "GND")
		(6 "In2.Cu" signal "VCC")
		(8 "In3.Cu" signal "VCC1")
		(10 "In4.Cu" signal "GND1")
		(12 "In5.Cu" signal "IN1")
		(14 "In6.Cu" signal "GND2")
		(16 "In7.Cu" signal "IN2")
		(18 "In8.Cu" signal "GND3")
		(20 "In9.Cu" signal "IN3")
		(22 "In10.Cu" signal "GND4")
		(24 "In11.Cu" signal "IN4")
		(26 "In12.Cu" signal "GND5")
		(28 "In13.Cu" signal "IN5")
		(30 "In14.Cu" signal "GND6")
		(32 "In15.Cu" signal "IN6")
		(34 "In16.Cu" signal "GND7")
		(2 "B.Cu" signal "BOTTOM")
		(9 "F.Adhes" user "F.Adhesive")
		(11 "B.Adhes" user "B.Adhesive")
		(13 "F.Paste" user "Package Geometry/Pastemask Top")
		(15 "B.Paste" user "Package Geometry/Pastemask Bottom")
		(5 "F.SilkS" user "Ref Des/Silkscreen Top")
		(7 "B.SilkS" user "Ref Des/Silkscreen Bottom")
		(1 "F.Mask" user "Board Geometry/Soldermask Top")
		(3 "B.Mask" user "Board Geometry/Soldermask Bottom")
		(17 "Dwgs.User" user "User.Drawings")
		(19 "Cmts.User" user "User.Comments")
		(21 "Eco1.User" user "User.Eco1")
		(23 "Eco2.User" user "User.Eco2")
		(25 "Edge.Cuts" user "Board Geometry/Outline")
		(27 "Margin" user)
		(31 "F.CrtYd" user "Package Geometry/Place Bound Top")
		(29 "B.CrtYd" user "Package Geometry/Place Bound Bottom")
		(35 "F.Fab" user "Ref Des/Assembly Top")
		(33 "B.Fab" user "Ref Des/Assembly Bottom")
	)
	(footprint ""
		(layer "F.Cu")
		(at 148.809202 -26.03373)
		(property "Reference" "R4062"
			(at 0 0 0)
			(layer "F.SilkS")
			(hide yes)
			(effects
				(font
					(size 1.27 1.27)
				)
			)
		)
		(property "Value" ""
			(at 0 0 0)
			(layer "F.Fab")
			(effects
				(font
					(size 1.27 1.27)
				)
			)
		)
		(duplicate_pad_numbers_are_jumpers no)
		(fp_line
			(start -0.7874 -0.4064)
			(end 0.7874 -0.4064)
			(stroke
				(width 0.1524)
				(type default)
			)
			(layer "F.SilkS")
		)
		(fp_line
			(start -0.7874 0.4064)
			(end -0.7874 -0.4064)
			(stroke
				(width 0.1524)
				(type default)
			)
			(layer "F.SilkS")
		)
		(fp_line
			(start 0.7874 -0.4064)
			(end 0.7874 0.4064)
			(stroke
				(width 0.1524)
				(type default)
			)
			(layer "F.SilkS")
		)
		(fp_line
			(start 0.7874 0.4064)
			(end -0.7874 0.4064)
			(stroke
				(width 0.1524)
				(type default)
			)
			(layer "F.SilkS")
		)
		(fp_line
			(start -0.67945 -0.305054)
			(end -0.12065 -0.305054)
			(stroke
				(width 0.1)
				(type default)
			)
			(layer "F.Fab")
		)
		(fp_line
			(start -0.67945 0.3048)
			(end -0.67945 -0.305054)
			(stroke
				(width 0.1)
				(type default)
			)
			(layer "F.Fab")
		)
		(fp_line
			(start -0.12065 -0.305054)
			(end -0.12065 -0.2794)
			(stroke
				(width 0.1)
				(type default)
			)
			(layer "F.Fab")
		)
		(fp_line
			(start -0.12065 -0.2794)
			(end 0.12065 -0.2794)
			(stroke
				(width 0.1)
				(type default)
			)
			(layer "F.Fab")
		)
		(fp_line
			(start -0.12065 0.2794)
			(end -0.12065 0.3048)
			(stroke
				(width 0.1)
				(type default)
			)
			(layer "F.Fab")
		)
		(fp_line
			(start -0.12065 0.3048)
			(end -0.67945 0.3048)
			(stroke
				(width 0.1)
				(type default)
			)
			(layer "F.Fab")
		)
		(fp_line
			(start 0.120396 0.2794)
			(end -0.12065 0.2794)
			(stroke
				(width 0.1)
				(type default)
			)
			(layer "F.Fab")
		)
		(fp_line
			(start 0.120396 0.3048)
			(end 0.120396 0.2794)
			(stroke
				(width 0.1)
				(type default)
			)
			(layer "F.Fab")
		)
		(fp_line
			(start 0.12065 -0.3048)
			(end 0.67945 -0.3048)
			(stroke
				(width 0.1)
				(type default)
			)
			(layer "F.Fab")
		)
		(fp_line
			(start 0.12065 -0.2794)
			(end 0.12065 -0.3048)
			(stroke
				(width 0.1)
				(type default)
			)
			(layer "F.Fab")
		)
		(fp_line
			(start 0.67945 -0.3048)
			(end 0.67945 0.3048)
			(stroke
				(width 0.1)
				(type default)
			)
			(layer "F.Fab")
		)
		(fp_line
			(start 0.67945 0.3048)
			(end 0.120396 0.3048)
			(stroke
				(width 0.1)
				(type default)
			)
			(layer "F.Fab")
		)
		(pad "1" smd circle
			(at -0.40005 0)
			(size 0 0)
			(layers "F.Cu" "F.Mask" "F.Paste")
			(net "P3V3_AUX")
		)
		(pad "2" smd circle
			(at 0.40005 0)
			(size 0 0)
			(layers "F.Cu" "F.Mask" "F.Paste")
			(net "PRSNT_SSD5_R_N")
		)
	)
	(footprint ""
		(layer "F.Cu")
		(at 359.508044 -86.490048)
		(property "Reference" "U125"
			(at -2.1844 -4.587748 0)
			(unlocked yes)
			(layer "F.SilkS")
			(effects
				(font
					(size 0.7874 0.5842)
					(thickness 0.1524)
				)
				(justify left)
			)
		)
		(property "Value" ""
			(at 0 0 0)
			(layer "F.Fab")
			(effects
				(font
					(size 1.27 1.27)
				)
			)
		)
		(duplicate_pad_numbers_are_jumpers no)
		(fp_line
			(start -1.8542 -3.949954)
			(end -1.8542 3.949954)
			(stroke
				(width 0.1524)
				(type default)
			)
			(layer "F.SilkS")
		)
		(fp_line
			(start -1.8542 3.949954)
			(end 1.8542 3.949954)
			(stroke
				(width 0.1524)
				(type default)
			)
			(layer "F.SilkS")
		)
		(fp_line
			(start -1.282954 -3.949954)
			(end -1.8542 -3.949954)
			(stroke
				(width 0.1524)
				(type default)
			)
			(layer "F.SilkS")
		)
		(fp_line
			(start 0 -2.667)
			(end -1.282954 -3.949954)
			(stroke
				(width 0.1524)
				(type default)
			)
			(layer "F.SilkS")
		)
		(fp_line
			(start 1.282954 -3.949954)
			(end 0 -2.667)
			(stroke
				(width 0.1524)
				(type default)
			)
			(layer "F.SilkS")
		)
		(fp_line
			(start 1.8542 -3.949954)
			(end 1.282954 -3.949954)
			(stroke
				(width 0.1524)
				(type default)
			)
			(layer "F.SilkS")
		)
		(fp_line
			(start 1.8542 3.949954)
			(end 1.8542 -3.949954)
			(stroke
				(width 0.1524)
				(type default)
			)
			(layer "F.SilkS")
		)
		(fp_poly
			(pts
				(xy -4.8006 -4.08305) (xy -4.8006 -3.06705) (xy -3.7846 -3.57505)
			)
			(stroke
				(width 0)
				(type default)
			)
			(fill yes)
			(layer "F.SilkS")
		)
		(fp_line
			(start -2.249932 -3.949954)
			(end -2.249932 3.949954)
			(stroke
				(width 0.1)
				(type default)
			)
			(layer "F.Fab")
		)
		(fp_line
			(start -2.249932 3.949954)
			(end 2.249932 3.949954)
			(stroke
				(width 0.1)
				(type default)
			)
			(layer "F.Fab")
		)
		(fp_line
			(start 2.249932 -3.949954)
			(end -2.249932 -3.949954)
			(stroke
				(width 0.1)
				(type default)
			)
			(layer "F.Fab")
		)
		(fp_line
			(start 2.249932 3.949954)
			(end 2.249932 -3.949954)
			(stroke
				(width 0.1)
				(type default)
			)
			(layer "F.Fab")
		)
		(fp_poly
			(pts
				(xy -4.8006 -4.08305) (xy -4.8006 -3.06705) (xy -3.7846 -3.57505)
			)
			(stroke
				(width 0)
				(type default)
			)
			(fill yes)
			(layer "F.Fab")
		)
		(pad "1" smd rect
			(at -2.800096 -3.57505 270)
			(size 0.3048 1.6002)
			(layers "F.Cu" "F.Mask" "F.Paste")
			(net "BIC_I2C9_SSD_MUX1_A0")
		)
		(pad "2" smd rect
			(at -2.800096 -2.925064 270)
			(size 0.3048 1.6002)
			(layers "F.Cu" "F.Mask" "F.Paste")
			(net "BIC_I2C9_SSD_MUX1_A1")
		)
		(pad "3" smd rect
			(at -2.800096 -2.275078 270)
			(size 0.3048 1.6002)
			(layers "F.Cu" "F.Mask" "F.Paste")
			(net "RST_BIC_I2C9_SSD_MUX1_R_N")
		)
		(pad "4" smd rect
			(at -2.800096 -1.625092 270)
			(size 0.3048 1.6002)
			(layers "F.Cu" "F.Mask" "F.Paste")
			(net "SMB_BIC_I2C9_MUX1_SSD8_SDA")
		)
		(pad "5" smd rect
			(at -2.800096 -0.975106 270)
			(size 0.3048 1.6002)
			(layers "F.Cu" "F.Mask" "F.Paste")
			(net "SMB_BIC_I2C9_MUX1_SSD8_SCL")
		)
		(pad "6" smd rect
			(at -2.800096 -0.32512 270)
			(size 0.3048 1.6002)
			(layers "F.Cu" "F.Mask" "F.Paste")
			(net "SMB_BIC_I2C9_MUX1_SSD9_SDA")
		)
		(pad "7" smd rect
			(at -2.800096 0.32512 270)
			(size 0.3048 1.6002)
			(layers "F.Cu" "F.Mask" "F.Paste")
			(net "SMB_BIC_I2C9_MUX1_SSD9_SCL")
		)
		(pad "8" smd rect
			(at -2.800096 0.975106 270)
			(size 0.3048 1.6002)
			(layers "F.Cu" "F.Mask" "F.Paste")
			(net "SMB_BIC_I2C9_MUX1_SSD10_SDA")
		)
		(pad "9" smd rect
			(at -2.800096 1.625092 270)
			(size 0.3048 1.6002)
			(layers "F.Cu" "F.Mask" "F.Paste")
			(net "SMB_BIC_I2C9_MUX1_SSD10_SCL")
		)
		(pad "10" smd rect
			(at -2.800096 2.275078 270)
			(size 0.3048 1.6002)
			(layers "F.Cu" "F.Mask" "F.Paste")
			(net "SMB_BIC_I2C9_MUX1_SSD11_SDA")
		)
		(pad "11" smd rect
			(at -2.800096 2.925064 270)
			(size 0.3048 1.6002)
			(layers "F.Cu" "F.Mask" "F.Paste")
			(net "SMB_BIC_I2C9_MUX1_SSD11_SCL")
		)
		(pad "12" smd rect
			(at -2.800096 3.57505 270)
			(size 0.3048 1.6002)
			(layers "F.Cu" "F.Mask" "F.Paste")
			(net "GND")
		)
		(pad "13" smd rect
			(at 2.800096 3.57505 270)
			(size 0.3048 1.6002)
			(layers "F.Cu" "F.Mask" "F.Paste")
			(net "SMB_BIC_I2C9_MUX1_SSD12_SDA")
		)
		(pad "14" smd rect
			(at 2.800096 2.925064 270)
			(size 0.3048 1.6002)
			(layers "F.Cu" "F.Mask" "F.Paste")
			(net "SMB_BIC_I2C9_MUX1_SSD12_SCL")
		)
		(pad "15" smd rect
			(at 2.800096 2.275078 270)
			(size 0.3048 1.6002)
			(layers "F.Cu" "F.Mask" "F.Paste")
			(net "SMB_BIC_I2C9_MUX1_SSD13_SDA")
		)
		(pad "16" smd rect
			(at 2.800096 1.625092 270)
			(size 0.3048 1.6002)
			(layers "F.Cu" "F.Mask" "F.Paste")
			(net "SMB_BIC_I2C9_MUX1_SSD13_SCL")
		)
		(pad "17" smd rect
			(at 2.800096 0.975106 270)
			(size 0.3048 1.6002)
			(layers "F.Cu" "F.Mask" "F.Paste")
			(net "SMB_BIC_I2C9_MUX1_SSD14_SDA")
		)
		(pad "18" smd rect
			(at 2.800096 0.32512 270)
			(size 0.3048 1.6002)
			(layers "F.Cu" "F.Mask" "F.Paste")
			(net "SMB_BIC_I2C9_MUX1_SSD14_SCL")
		)
		(pad "19" smd rect
			(at 2.800096 -0.32512 270)
			(size 0.3048 1.6002)
			(layers "F.Cu" "F.Mask" "F.Paste")
			(net "SMB_BIC_I2C9_MUX1_SSD15_SDA")
		)
		(pad "20" smd rect
			(at 2.800096 -0.975106 270)
			(size 0.3048 1.6002)
			(layers "F.Cu" "F.Mask" "F.Paste")
			(net "SMB_BIC_I2C9_MUX1_SSD15_SCL")
		)
		(pad "21" smd rect
			(at 2.800096 -1.625092 270)
			(size 0.3048 1.6002)
			(layers "F.Cu" "F.Mask" "F.Paste")
			(net "BIC_I2C9_SSD_MUX1_A2")
		)
		(pad "22" smd rect
			(at 2.800096 -2.275078 270)
			(size 0.3048 1.6002)
			(layers "F.Cu" "F.Mask" "F.Paste")
			(net "SMB_BIC_I2C9_SSD_MUX1_SCL")
		)
		(pad "23" smd rect
			(at 2.800096 -2.925064 270)
			(size 0.3048 1.6002)
			(layers "F.Cu" "F.Mask" "F.Paste")
			(net "SMB_BIC_I2C9_SSD_MUX1_SDA")
		)
		(pad "24" smd rect
			(at 2.800096 -3.57505 270)
			(size 0.3048 1.6002)
			(layers "F.Cu" "F.Mask" "F.Paste")
			(net "P3V3_AUX")
		)
	)
	(footprint ""
		(layer "F.Cu")
		(at 185.89244 -29.139642 180)
		(property "Reference" "C298"
			(at 0 0 180)
			(layer "F.SilkS")
			(hide yes)
			(effects
				(font
					(size 1.27 1.27)
				)
			)
		)
		(property "Value" ""
			(at 0 0 180)
			(layer "F.Fab")
			(effects
				(font
					(size 1.27 1.27)
				)
			)
		)
		(duplicate_pad_numbers_are_jumpers no)
		(fp_line
			(start 0.299974 0.150114)
			(end -0.299974 0.150114)
			(stroke
				(width 0.1)
				(type default)
			)
			(layer "F.Fab")
		)
		(fp_line
			(start 0.299974 -0.150114)
			(end 0.299974 0.150114)
			(stroke
				(width 0.1)
				(type default)
			)
			(layer "F.Fab")
		)
		(fp_line
			(start -0.299974 0.150114)
			(end -0.299974 -0.150114)
			(stroke
				(width 0.1)
				(type default)
			)
			(layer "F.Fab")
		)
		(fp_line
			(start -0.299974 -0.150114)
			(end 0.299974 -0.150114)
			(stroke
				(width 0.1)
				(type default)
			)
			(layer "F.Fab")
		)
		(pad "1" smd rect
			(at -0.2667 0 180)
			(size 0.3048 0.381)
			(layers "F.Cu" "F.Mask" "F.Paste")
			(net "P5E_PEX1_STN2_TX_DP<36>")
		)
		(pad "2" smd rect
			(at 0.2667 0 180)
			(size 0.3048 0.381)
			(layers "F.Cu" "F.Mask" "F.Paste")
			(net "P5E_PEX1_STN2_TX_C_DP<36>")
		)
	)
	(footprint ""
		(layer "F.Cu")
		(at 421.705532 -350.098614 90)
		(property "Reference" "C2451"
			(at 0 0 90)
			(layer "F.SilkS")
			(hide yes)
			(effects
				(font
					(size 1.27 1.27)
				)
			)
		)
		(property "Value" ""
			(at 0 0 90)
			(layer "F.Fab")
			(effects
				(font
					(size 1.27 1.27)
				)
			)
		)
		(duplicate_pad_numbers_are_jumpers no)
		(fp_line
			(start 0.299974 -0.150114)
			(end 0.299974 0.150114)
			(stroke
				(width 0.1)
				(type default)
			)
			(layer "F.Fab")
		)
		(fp_line
			(start -0.299974 -0.150114)
			(end 0.299974 -0.150114)
			(stroke
				(width 0.1)
				(type default)
			)
			(layer "F.Fab")
		)
		(fp_line
			(start 0.299974 0.150114)
			(end -0.299974 0.150114)
			(stroke
				(width 0.1)
				(type default)
			)
			(layer "F.Fab")
		)
		(fp_line
			(start -0.299974 0.150114)
			(end -0.299974 -0.150114)
			(stroke
				(width 0.1)
				(type default)
			)
			(layer "F.Fab")
		)
		(pad "1" smd rect
			(at -0.2667 0 90)
			(size 0.3048 0.381)
			(layers "F.Cu" "F.Mask" "F.Paste")
			(net "P5E_PEX3_STN4_TX_DP<73>")
		)
		(pad "2" smd rect
			(at 0.2667 0 90)
			(size 0.3048 0.381)
			(layers "F.Cu" "F.Mask" "F.Paste")
			(net "P5E_PEX3_STN4_TX_C_DP<73>")
		)
	)
	(footprint ""
		(layer "F.Cu")
		(at 37.550344 -252.356874 -90)
		(property "Reference" "R1216"
			(at 0 0 270)
			(layer "F.SilkS")
			(hide yes)
			(effects
				(font
					(size 1.27 1.27)
				)
			)
		)
		(property "Value" ""
			(at 0 0 270)
			(layer "F.Fab")
			(effects
				(font
					(size 1.27 1.27)
				)
			)
		)
		(duplicate_pad_numbers_are_jumpers no)
		(fp_line
			(start -0.7874 0.4064)
			(end -0.7874 -0.4064)
			(stroke
				(width 0.1524)
				(type default)
			)
			(layer "F.SilkS")
		)
		(fp_line
			(start 0.7874 0.4064)
			(end -0.7874 0.4064)
			(stroke
				(width 0.1524)
				(type default)
			)
			(layer "F.SilkS")
		)
		(fp_line
			(start -0.7874 -0.4064)
			(end 0.7874 -0.4064)
			(stroke
				(width 0.1524)
				(type default)
			)
			(layer "F.SilkS")
		)
		(fp_line
			(start 0.7874 -0.4064)
			(end 0.7874 0.4064)
			(stroke
				(width 0.1524)
				(type default)
			)
			(layer "F.SilkS")
		)
		(fp_line
			(start -0.67945 0.3048)
			(end -0.67945 -0.305054)
			(stroke
				(width 0.1)
				(type default)
			)
			(layer "F.Fab")
		)
		(fp_line
			(start -0.12065 0.3048)
			(end -0.67945 0.3048)
			(stroke
				(width 0.1)
				(type default)
			)
			(layer "F.Fab")
		)
		(fp_line
			(start 0.120396 0.3048)
			(end 0.120396 0.2794)
			(stroke
				(width 0.1)
				(type default)
			)
			(layer "F.Fab")
		)
		(fp_line
			(start 0.67945 0.3048)
			(end 0.120396 0.3048)
			(stroke
				(width 0.1)
				(type default)
			)
			(layer "F.Fab")
		)
		(fp_line
			(start -0.12065 0.2794)
			(end -0.12065 0.3048)
			(stroke
				(width 0.1)
				(type default)
			)
			(layer "F.Fab")
		)
		(fp_line
			(start 0.120396 0.2794)
			(end -0.12065 0.2794)
			(stroke
				(width 0.1)
				(type default)
			)
			(layer "F.Fab")
		)
		(fp_line
			(start -0.12065 -0.2794)
			(end 0.12065 -0.2794)
			(stroke
				(width 0.1)
				(type default)
			)
			(layer "F.Fab")
		)
		(fp_line
			(start 0.12065 -0.2794)
			(end 0.12065 -0.3048)
			(stroke
				(width 0.1)
				(type default)
			)
			(layer "F.Fab")
		)
		(fp_line
			(start 0.12065 -0.3048)
			(end 0.67945 -0.3048)
			(stroke
				(width 0.1)
				(type default)
			)
			(layer "F.Fab")
		)
		(fp_line
			(start 0.67945 -0.3048)
			(end 0.67945 0.3048)
			(stroke
				(width 0.1)
				(type default)
			)
			(layer "F.Fab")
		)
		(fp_line
			(start -0.67945 -0.305054)
			(end -0.12065 -0.305054)
			(stroke
				(width 0.1)
				(type default)
			)
			(layer "F.Fab")
		)
		(fp_line
			(start -0.12065 -0.305054)
			(end -0.12065 -0.2794)
			(stroke
				(width 0.1)
				(type default)
			)
			(layer "F.Fab")
		)
		(pad "1" smd circle
			(at -0.40005 0 270)
			(size 0 0)
			(layers "F.Cu" "F.Mask" "F.Paste")
			(net "GND")
		)
		(pad "2" smd circle
			(at 0.40005 0 270)
			(size 0 0)
			(layers "F.Cu" "F.Mask" "F.Paste")
			(net "PEX0_MODE_SEL10")
		)
	)
	(footprint ""
		(layer "F.Cu")
		(at 211.939886 -70.52437 90)
		(property "Reference" "PC395"
			(at 0 0 90)
			(layer "F.SilkS")
			(hide yes)
			(effects
				(font
					(size 1.27 1.27)
				)
			)
		)
		(property "Value" ""
			(at 0 0 90)
			(layer "F.Fab")
			(effects
				(font
					(size 1.27 1.27)
				)
			)
		)
		(duplicate_pad_numbers_are_jumpers no)
		(fp_line
			(start 1.524 -0.762)
			(end 1.524 0.762)
			(stroke
				(width 0.1524)
				(type default)
			)
			(layer "F.SilkS")
		)
		(fp_line
			(start -1.524 -0.762)
			(end 1.524 -0.762)
			(stroke
				(width 0.1524)
				(type default)
			)
			(layer "F.SilkS")
		)
		(fp_line
			(start 1.524 0.762)
			(end -1.524 0.762)
			(stroke
				(width 0.1524)
				(type default)
			)
			(layer "F.SilkS")
		)
		(fp_line
			(start -1.524 0.762)
			(end -1.524 -0.762)
			(stroke
				(width 0.1524)
				(type default)
			)
			(layer "F.SilkS")
		)
		(fp_line
			(start 1.1049 -0.724916)
			(end -1.1049 -0.724916)
			(stroke
				(width 0.1)
				(type default)
			)
			(layer "F.Fab")
		)
		(fp_line
			(start -1.1049 -0.724916)
			(end -1.1049 0.724916)
			(stroke
				(width 0.1)
				(type default)
			)
			(layer "F.Fab")
		)
		(fp_line
			(start 1.1049 0.724916)
			(end 1.1049 -0.724916)
			(stroke
				(width 0.1)
				(type default)
			)
			(layer "F.Fab")
		)
		(fp_line
			(start -1.1049 0.724916)
			(end 1.1049 0.724916)
			(stroke
				(width 0.1)
				(type default)
			)
			(layer "F.Fab")
		)
		(pad "1" smd rect
			(at -0.889 0 270)
			(size 1.016 1.27)
			(layers "F.Cu" "F.Mask" "F.Paste")
			(net "P12V_SSD7_R")
		)
		(pad "2" smd rect
			(at 0.889 0 270)
			(size 1.016 1.27)
			(layers "F.Cu" "F.Mask" "F.Paste")
			(net "GND")
		)
	)
)
